(kicad_pcb
	(version 20260206)
	(generator "pcbnew")
	(generator_version "10.0")
	(general
		(thickness 1.6)
		(legacy_teardrops no)
	)
	(paper "A4")
	(title_block
		(title "04192023_DAF0TMB3IC0_F0TG_MB_C_brd_V02_OCP.brd")
		(comment 1 "Grand Teton / footprints 1930-1935 of 8354")
	)
	(layers
		(0 "F.Cu" signal "TOP")
		(4 "In1.Cu" signal "GND")
		(6 "In2.Cu" signal "IN1")
		(8 "In3.Cu" signal "GND1")
		(10 "In4.Cu" signal "IN2")
		(12 "In5.Cu" signal "GND2")
		(14 "In6.Cu" signal "IN3")
		(16 "In7.Cu" signal "GND3")
		(18 "In8.Cu" signal "VCC")
		(20 "In9.Cu" signal "VCC1")
		(22 "In10.Cu" signal "GND4")
		(24 "In11.Cu" signal "IN4")
		(26 "In12.Cu" signal "GND5")
		(28 "In13.Cu" signal "IN5")
		(30 "In14.Cu" signal "GND6")
		(32 "In15.Cu" signal "IN6")
		(34 "In16.Cu" signal "GND7")
		(2 "B.Cu" signal "BOTTOM")
		(9 "F.Adhes" user "F.Adhesive")
		(11 "B.Adhes" user "B.Adhesive")
		(13 "F.Paste" user "Package Geometry/Pastemask Top")
		(15 "B.Paste" user "Package Geometry/Pastemask Bottom")
		(5 "F.SilkS" user "Ref Des/Silkscreen Top")
		(7 "B.SilkS" user "Ref Des/Silkscreen Bottom")
		(1 "F.Mask" user "Board Geometry/Soldermask Top")
		(3 "B.Mask" user "Board Geometry/Soldermask Bottom")
		(17 "Dwgs.User" user "User.Drawings")
		(19 "Cmts.User" user "User.Comments")
		(21 "Eco1.User" user "User.Eco1")
		(23 "Eco2.User" user "User.Eco2")
		(25 "Edge.Cuts" user "Board Geometry/Outline")
		(27 "Margin" user)
		(31 "F.CrtYd" user "Package Geometry/Place Bound Top")
		(29 "B.CrtYd" user "Package Geometry/Place Bound Bottom")
		(35 "F.Fab" user "Ref Des/Assembly Top")
		(33 "B.Fab" user "Ref Des/Assembly Bottom")
	)
	(footprint ""
		(layer "F.Cu")
		(at 423.56278 -106.129328 90)
		(property "Reference" "PC2163"
			(at 0 0 90)
			(layer "F.SilkS")
			(hide yes)
			(effects
				(font
					(size 1.27 1.27)
				)
			)
		)
		(property "Value" ""
			(at 0 0 90)
			(layer "F.Fab")
			(effects
				(font
					(size 1.27 1.27)
				)
			)
		)
		(duplicate_pad_numbers_are_jumpers no)
		(fp_line
			(start 1.524 -0.762)
			(end 1.524 0.762)
			(stroke
				(width 0.1524)
				(type default)
			)
			(layer "F.SilkS")
		)
		(fp_line
			(start -1.524 -0.762)
			(end 1.524 -0.762)
			(stroke
				(width 0.1524)
				(type default)
			)
			(layer "F.SilkS")
		)
		(fp_line
			(start 1.524 0.762)
			(end -1.524 0.762)
			(stroke
				(width 0.1524)
				(type default)
			)
			(layer "F.SilkS")
		)
		(fp_line
			(start -1.524 0.762)
			(end -1.524 -0.762)
			(stroke
				(width 0.1524)
				(type default)
			)
			(layer "F.SilkS")
		)
		(fp_line
			(start 1.1049 -0.724916)
			(end -1.1049 -0.724916)
			(stroke
				(width 0.1)
				(type default)
			)
			(layer "F.Fab")
		)
		(fp_line
			(start -1.1049 -0.724916)
			(end -1.1049 0.724916)
			(stroke
				(width 0.1)
				(type default)
			)
			(layer "F.Fab")
		)
		(fp_line
			(start 1.1049 0.724916)
			(end 1.1049 -0.724916)
			(stroke
				(width 0.1)
				(type default)
			)
			(layer "F.Fab")
		)
		(fp_line
			(start -1.1049 0.724916)
			(end 1.1049 0.724916)
			(stroke
				(width 0.1)
				(type default)
			)
			(layer "F.Fab")
		)
		(pad "1" smd rect
			(at -0.889 0 270)
			(size 1.016 1.27)
			(layers "F.Cu" "F.Mask" "F.Paste")
			(net "P3V3_OCP_SFF_R")
		)
		(pad "2" smd rect
			(at 0.889 0 270)
			(size 1.016 1.27)
			(layers "F.Cu" "F.Mask" "F.Paste")
			(net "GND")
		)
	)
	(footprint ""
		(layer "F.Cu")
		(at 184.5945 -408.110182 180)
		(property "Reference" "PR3926"
			(at 0 0 180)
			(layer "F.SilkS")
			(hide yes)
			(effects
				(font
					(size 1.27 1.27)
				)
			)
		)
		(property "Value" ""
			(at 0 0 180)
			(layer "F.Fab")
			(effects
				(font
					(size 1.27 1.27)
				)
			)
		)
		(duplicate_pad_numbers_are_jumpers no)
		(fp_line
			(start 0.7874 0.4064)
			(end -0.7874 0.4064)
			(stroke
				(width 0.1524)
				(type default)
			)
			(layer "F.SilkS")
		)
		(fp_line
			(start 0.7874 -0.4064)
			(end 0.7874 0.4064)
			(stroke
				(width 0.1524)
				(type default)
			)
			(layer "F.SilkS")
		)
		(fp_line
			(start -0.7874 0.4064)
			(end -0.7874 -0.4064)
			(stroke
				(width 0.1524)
				(type default)
			)
			(layer "F.SilkS")
		)
		(fp_line
			(start -0.7874 -0.4064)
			(end 0.7874 -0.4064)
			(stroke
				(width 0.1524)
				(type default)
			)
			(layer "F.SilkS")
		)
		(fp_line
			(start 0.67945 0.3048)
			(end 0.120396 0.3048)
			(stroke
				(width 0.1)
				(type default)
			)
			(layer "F.Fab")
		)
		(fp_line
			(start 0.67945 -0.3048)
			(end 0.67945 0.3048)
			(stroke
				(width 0.1)
				(type default)
			)
			(layer "F.Fab")
		)
		(fp_line
			(start 0.12065 -0.2794)
			(end 0.12065 -0.3048)
			(stroke
				(width 0.1)
				(type default)
			)
			(layer "F.Fab")
		)
		(fp_line
			(start 0.12065 -0.3048)
			(end 0.67945 -0.3048)
			(stroke
				(width 0.1)
				(type default)
			)
			(layer "F.Fab")
		)
		(fp_line
			(start 0.120396 0.3048)
			(end 0.120396 0.2794)
			(stroke
				(width 0.1)
				(type default)
			)
			(layer "F.Fab")
		)
		(fp_line
			(start 0.120396 0.2794)
			(end -0.12065 0.2794)
			(stroke
				(width 0.1)
				(type default)
			)
			(layer "F.Fab")
		)
		(fp_line
			(start -0.12065 0.3048)
			(end -0.67945 0.3048)
			(stroke
				(width 0.1)
				(type default)
			)
			(layer "F.Fab")
		)
		(fp_line
			(start -0.12065 0.2794)
			(end -0.12065 0.3048)
			(stroke
				(width 0.1)
				(type default)
			)
			(layer "F.Fab")
		)
		(fp_line
			(start -0.12065 -0.2794)
			(end 0.12065 -0.2794)
			(stroke
				(width 0.1)
				(type default)
			)
			(layer "F.Fab")
		)
		(fp_line
			(start -0.12065 -0.305054)
			(end -0.12065 -0.2794)
			(stroke
				(width 0.1)
				(type default)
			)
			(layer "F.Fab")
		)
		(fp_line
			(start -0.67945 0.3048)
			(end -0.67945 -0.305054)
			(stroke
				(width 0.1)
				(type default)
			)
			(layer "F.Fab")
		)
		(fp_line
			(start -0.67945 -0.305054)
			(end -0.12065 -0.305054)
			(stroke
				(width 0.1)
				(type default)
			)
			(layer "F.Fab")
		)
		(pad "1" smd circle
			(at -0.40005 0 180)
			(size 0 0)
			(layers "F.Cu" "F.Mask" "F.Paste")
			(net "P12V_PSU")
		)
		(pad "2" smd circle
			(at 0.40005 0 180)
			(size 0 0)
			(layers "F.Cu" "F.Mask" "F.Paste")
			(net "HSC_VSENSE")
		)
	)
	(footprint ""
		(layer "F.Cu")
		(at 219.99956 -103.17226 180)
		(property "Reference" "U9050"
			(at -3.35915 -1.37668 90)
			(unlocked yes)
			(layer "F.SilkS")
			(effects
				(font
					(size 0.7874 0.5842)
					(thickness 0.1524)
				)
				(justify left)
			)
		)
		(property "Value" ""
			(at 0 0 180)
			(layer "F.Fab")
			(effects
				(font
					(size 1.27 1.27)
				)
			)
		)
		(duplicate_pad_numbers_are_jumpers no)
		(fp_line
			(start 1.733296 1.549908)
			(end 1.733296 -1.549908)
			(stroke
				(width 0.1524)
				(type default)
			)
			(layer "F.SilkS")
		)
		(fp_line
			(start 1.733296 -1.549908)
			(end 0.660908 -1.549908)
			(stroke
				(width 0.1524)
				(type default)
			)
			(layer "F.SilkS")
		)
		(fp_line
			(start 0.660908 -1.549908)
			(end 0 -0.889)
			(stroke
				(width 0.1524)
				(type default)
			)
			(layer "F.SilkS")
		)
		(fp_line
			(start 0 -0.889)
			(end -0.660908 -1.549908)
			(stroke
				(width 0.1524)
				(type default)
			)
			(layer "F.SilkS")
		)
		(fp_line
			(start -0.660908 -1.549908)
			(end -1.733296 -1.549908)
			(stroke
				(width 0.1524)
				(type default)
			)
			(layer "F.SilkS")
		)
		(fp_line
			(start -1.733296 1.549908)
			(end 1.733296 1.549908)
			(stroke
				(width 0.1524)
				(type default)
			)
			(layer "F.SilkS")
		)
		(fp_line
			(start -1.733296 -1.549908)
			(end -1.733296 1.549908)
			(stroke
				(width 0.1524)
				(type default)
			)
			(layer "F.SilkS")
		)
		(fp_poly
			(pts
				(xy -2.4384 -1.20396) (xy -2.4384 -0.69596) (xy -1.9304 -0.94996)
			)
			(stroke
				(width 0)
				(type default)
			)
			(fill yes)
			(layer "F.SilkS")
		)
		(fp_line
			(start 0.849884 1.549908)
			(end 0.849884 -1.549908)
			(stroke
				(width 0.1)
				(type default)
			)
			(layer "F.Fab")
		)
		(fp_line
			(start 0.849884 -1.549908)
			(end -0.849884 -1.549908)
			(stroke
				(width 0.1)
				(type default)
			)
			(layer "F.Fab")
		)
		(fp_line
			(start -0.849884 1.549908)
			(end 0.849884 1.549908)
			(stroke
				(width 0.1)
				(type default)
			)
			(layer "F.Fab")
		)
		(fp_line
			(start -0.849884 -1.549908)
			(end -0.849884 1.549908)
			(stroke
				(width 0.1)
				(type default)
			)
			(layer "F.Fab")
		)
		(fp_poly
			(pts
				(xy -2.4384 -1.20396) (xy -2.4384 -0.69596) (xy -1.9304 -0.94996)
			)
			(stroke
				(width 0)
				(type default)
			)
			(fill yes)
			(layer "F.Fab")
		)
		(pad "1" smd rect
			(at -1.199896 -0.94996 90)
			(size 0.5588 0.8128)
			(layers "F.Cu" "F.Mask" "F.Paste")
			(net "OCP_V3_1_P3V3_PWRGD")
		)
		(pad "2" smd rect
			(at -1.199896 0 90)
			(size 0.5588 0.8128)
			(layers "F.Cu" "F.Mask" "F.Paste")
			(net "HP_LVC3_OCP_V3_1_P12V_R2_PWRGD")
		)
		(pad "3" smd rect
			(at -1.199896 0.94996 90)
			(size 0.5588 0.8128)
			(layers "F.Cu" "F.Mask" "F.Paste")
			(net "GND")
		)
		(pad "4" smd rect
			(at 1.199896 0.94996 90)
			(size 0.5588 0.8128)
			(layers "F.Cu" "F.Mask" "F.Paste")
			(net "HP_LVC3_OCP_V3_1_PWRGD_R2")
		)
		(pad "5" smd rect
			(at 1.199896 -0.94996 90)
			(size 0.5588 0.8128)
			(layers "F.Cu" "F.Mask" "F.Paste")
			(net "P3V3_AUX")
		)
	)
	(footprint ""
		(layer "F.Cu")
		(at 450.389752 -394.302234 180)
		(property "Reference" "PC6585"
			(at 0 0 180)
			(layer "F.SilkS")
			(hide yes)
			(effects
				(font
					(size 1.27 1.27)
				)
			)
		)
		(property "Value" ""
			(at 0 0 180)
			(layer "F.Fab")
			(effects
				(font
					(size 1.27 1.27)
				)
			)
		)
		(duplicate_pad_numbers_are_jumpers no)
		(fp_line
			(start 0.7874 0.4064)
			(end -0.7874 0.4064)
			(stroke
				(width 0.1524)
				(type default)
			)
			(layer "F.SilkS")
		)
		(fp_line
			(start 0.7874 -0.4064)
			(end 0.7874 0.4064)
			(stroke
				(width 0.1524)
				(type default)
			)
			(layer "F.SilkS")
		)
		(fp_line
			(start -0.7874 0.4064)
			(end -0.7874 -0.4064)
			(stroke
				(width 0.1524)
				(type default)
			)
			(layer "F.SilkS")
		)
		(fp_line
			(start -0.7874 -0.4064)
			(end 0.7874 -0.4064)
			(stroke
				(width 0.1524)
				(type default)
			)
			(layer "F.SilkS")
		)
		(fp_line
			(start 0.67945 0.3048)
			(end 0.120396 0.3048)
			(stroke
				(width 0.1)
				(type default)
			)
			(layer "F.Fab")
		)
		(fp_line
			(start 0.67945 -0.3048)
			(end 0.67945 0.3048)
			(stroke
				(width 0.1)
				(type default)
			)
			(layer "F.Fab")
		)
		(fp_line
			(start 0.12065 -0.2794)
			(end 0.12065 -0.3048)
			(stroke
				(width 0.1)
				(type default)
			)
			(layer "F.Fab")
		)
		(fp_line
			(start 0.12065 -0.3048)
			(end 0.67945 -0.3048)
			(stroke
				(width 0.1)
				(type default)
			)
			(layer "F.Fab")
		)
		(fp_line
			(start 0.120396 0.3048)
			(end 0.120396 0.2794)
			(stroke
				(width 0.1)
				(type default)
			)
			(layer "F.Fab")
		)
		(fp_line
			(start 0.120396 0.2794)
			(end -0.12065 0.2794)
			(stroke
				(width 0.1)
				(type default)
			)
			(layer "F.Fab")
		)
		(fp_line
			(start -0.12065 0.3048)
			(end -0.67945 0.3048)
			(stroke
				(width 0.1)
				(type default)
			)
			(layer "F.Fab")
		)
		(fp_line
			(start -0.12065 0.2794)
			(end -0.12065 0.3048)
			(stroke
				(width 0.1)
				(type default)
			)
			(layer "F.Fab")
		)
		(fp_line
			(start -0.12065 -0.2794)
			(end 0.12065 -0.2794)
			(stroke
				(width 0.1)
				(type default)
			)
			(layer "F.Fab")
		)
		(fp_line
			(start -0.12065 -0.305054)
			(end -0.12065 -0.2794)
			(stroke
				(width 0.1)
				(type default)
			)
			(layer "F.Fab")
		)
		(fp_line
			(start -0.67945 0.3048)
			(end -0.67945 -0.305054)
			(stroke
				(width 0.1)
				(type default)
			)
			(layer "F.Fab")
		)
		(fp_line
			(start -0.67945 -0.305054)
			(end -0.12065 -0.305054)
			(stroke
				(width 0.1)
				(type default)
			)
			(layer "F.Fab")
		)
		(pad "1" smd circle
			(at -0.40005 0 180)
			(size 0 0)
			(layers "F.Cu" "F.Mask" "F.Paste")
			(net "SW_P0V9_RETIMER_CPU0_SW2")
		)
		(pad "2" smd circle
			(at 0.40005 0 180)
			(size 0 0)
			(layers "F.Cu" "F.Mask" "F.Paste")
			(net "SW_P0V9_RETIMER_CPU0_SW2_RC")
		)
	)
	(footprint ""
		(layer "F.Cu")
		(at 91.986354 -177.464212)
		(property "Reference" "PR188"
			(at 0 0 0)
			(layer "F.SilkS")
			(hide yes)
			(effects
				(font
					(size 1.27 1.27)
				)
			)
		)
		(property "Value" ""
			(at 0 0 0)
			(layer "F.Fab")
			(effects
				(font
					(size 1.27 1.27)
				)
			)
		)
		(duplicate_pad_numbers_are_jumpers no)
		(fp_line
			(start -0.7874 -0.4064)
			(end 0.7874 -0.4064)
			(stroke
				(width 0.1524)
				(type default)
			)
			(layer "F.SilkS")
		)
		(fp_line
			(start -0.7874 0.4064)
			(end -0.7874 -0.4064)
			(stroke
				(width 0.1524)
				(type default)
			)
			(layer "F.SilkS")
		)
		(fp_line
			(start 0.7874 -0.4064)
			(end 0.7874 0.4064)
			(stroke
				(width 0.1524)
				(type default)
			)
			(layer "F.SilkS")
		)
		(fp_line
			(start 0.7874 0.4064)
			(end -0.7874 0.4064)
			(stroke
				(width 0.1524)
				(type default)
			)
			(layer "F.SilkS")
		)
		(fp_line
			(start -0.67945 -0.305054)
			(end -0.12065 -0.305054)
			(stroke
				(width 0.1)
				(type default)
			)
			(layer "F.Fab")
		)
		(fp_line
			(start -0.67945 0.3048)
			(end -0.67945 -0.305054)
			(stroke
				(width 0.1)
				(type default)
			)
			(layer "F.Fab")
		)
		(fp_line
			(start -0.12065 -0.305054)
			(end -0.12065 -0.2794)
			(stroke
				(width 0.1)
				(type default)
			)
			(layer "F.Fab")
		)
		(fp_line
			(start -0.12065 -0.2794)
			(end 0.12065 -0.2794)
			(stroke
				(width 0.1)
				(type default)
			)
			(layer "F.Fab")
		)
		(fp_line
			(start -0.12065 0.2794)
			(end -0.12065 0.3048)
			(stroke
				(width 0.1)
				(type default)
			)
			(layer "F.Fab")
		)
		(fp_line
			(start -0.12065 0.3048)
			(end -0.67945 0.3048)
			(stroke
				(width 0.1)
				(type default)
			)
			(layer "F.Fab")
		)
		(fp_line
			(start 0.120396 0.2794)
			(end -0.12065 0.2794)
			(stroke
				(width 0.1)
				(type default)
			)
			(layer "F.Fab")
		)
		(fp_line
			(start 0.120396 0.3048)
			(end 0.120396 0.2794)
			(stroke
				(width 0.1)
				(type default)
			)
			(layer "F.Fab")
		)
		(fp_line
			(start 0.12065 -0.3048)
			(end 0.67945 -0.3048)
			(stroke
				(width 0.1)
				(type default)
			)
			(layer "F.Fab")
		)
		(fp_line
			(start 0.12065 -0.2794)
			(end 0.12065 -0.3048)
			(stroke
				(width 0.1)
				(type default)
			)
			(layer "F.Fab")
		)
		(fp_line
			(start 0.67945 -0.3048)
			(end 0.67945 0.3048)
			(stroke
				(width 0.1)
				(type default)
			)
			(layer "F.Fab")
		)
		(fp_line
			(start 0.67945 0.3048)
			(end 0.120396 0.3048)
			(stroke
				(width 0.1)
				(type default)
			)
			(layer "F.Fab")
		)
		(pad "1" smd circle
			(at -0.40005 0)
			(size 0 0)
			(layers "F.Cu" "F.Mask" "F.Paste")
			(net "GND")
		)
		(pad "2" smd circle
			(at 0.40005 0)
			(size 0 0)
			(layers "F.Cu" "F.Mask" "F.Paste")
			(net "PVDDCR_CPU0_P1_LSET2")
		)
	)
	(footprint ""
		(layer "F.Cu")
		(at 300.736 -108.56595 -90)
		(property "Reference" "R1349"
			(at 0 0 270)
			(layer "F.SilkS")
			(hide yes)
			(effects
				(font
					(size 1.27 1.27)
				)
			)
		)
		(property "Value" ""
			(at 0 0 270)
			(layer "F.Fab")
			(effects
				(font
					(size 1.27 1.27)
				)
			)
		)
		(duplicate_pad_numbers_are_jumpers no)
		(fp_line
			(start -0.7874 0.4064)
			(end -0.7874 -0.4064)
			(stroke
				(width 0.1524)
				(type default)
			)
			(layer "F.SilkS")
		)
		(fp_line
			(start 0.7874 0.4064)
			(end -0.7874 0.4064)
			(stroke
				(width 0.1524)
				(type default)
			)
			(layer "F.SilkS")
		)
		(fp_line
			(start -0.7874 -0.4064)
			(end 0.7874 -0.4064)
			(stroke
				(width 0.1524)
				(type default)
			)
			(layer "F.SilkS")
		)
		(fp_line
			(start 0.7874 -0.4064)
			(end 0.7874 0.4064)
			(stroke
				(width 0.1524)
				(type default)
			)
			(layer "F.SilkS")
		)
		(fp_line
			(start -0.67945 0.3048)
			(end -0.67945 -0.305054)
			(stroke
				(width 0.1)
				(type default)
			)
			(layer "F.Fab")
		)
		(fp_line
			(start -0.12065 0.3048)
			(end -0.67945 0.3048)
			(stroke
				(width 0.1)
				(type default)
			)
			(layer "F.Fab")
		)
		(fp_line
			(start 0.120396 0.3048)
			(end 0.120396 0.2794)
			(stroke
				(width 0.1)
				(type default)
			)
			(layer "F.Fab")
		)
		(fp_line
			(start 0.67945 0.3048)
			(end 0.120396 0.3048)
			(stroke
				(width 0.1)
				(type default)
			)
			(layer "F.Fab")
		)
		(fp_line
			(start -0.12065 0.2794)
			(end -0.12065 0.3048)
			(stroke
				(width 0.1)
				(type default)
			)
			(layer "F.Fab")
		)
		(fp_line
			(start 0.120396 0.2794)
			(end -0.12065 0.2794)
			(stroke
				(width 0.1)
				(type default)
			)
			(layer "F.Fab")
		)
		(fp_line
			(start -0.12065 -0.2794)
			(end 0.12065 -0.2794)
			(stroke
				(width 0.1)
				(type default)
			)
			(layer "F.Fab")
		)
		(fp_line
			(start 0.12065 -0.2794)
			(end 0.12065 -0.3048)
			(stroke
				(width 0.1)
				(type default)
			)
			(layer "F.Fab")
		)
		(fp_line
			(start 0.12065 -0.3048)
			(end 0.67945 -0.3048)
			(stroke
				(width 0.1)
				(type default)
			)
			(layer "F.Fab")
		)
		(fp_line
			(start 0.67945 -0.3048)
			(end 0.67945 0.3048)
			(stroke
				(width 0.1)
				(type default)
			)
			(layer "F.Fab")
		)
		(fp_line
			(start -0.67945 -0.305054)
			(end -0.12065 -0.305054)
			(stroke
				(width 0.1)
				(type default)
			)
			(layer "F.Fab")
		)
		(fp_line
			(start -0.12065 -0.305054)
			(end -0.12065 -0.2794)
			(stroke
				(width 0.1)
				(type default)
			)
			(layer "F.Fab")
		)
		(pad "1" smd circle
			(at -0.40005 0 270)
			(size 0 0)
			(layers "F.Cu" "F.Mask" "F.Paste")
			(net "SMB_INA230_3V3AUX_SDA")
		)
		(pad "2" smd circle
			(at 0.40005 0 270)
			(size 0 0)
			(layers "F.Cu" "F.Mask" "F.Paste")
			(net "SMB_INA230_8_3V3AUX_SDA_R")
		)
	)
)
